# S9S_MB_2U (Grand Teton) — schematic netlist excerpt (pin names and nets, part order shuffled) for the footprints in the layout excerpt that follows; sources: Cadence DE-HDL packaged netlist, KiCad conversion of 03242023_DA0F0TMBIJ0_F0T_Motherboard_J_brd_V01_OCP.brd

PC2080  Q_CAP  22UF 16V 20% X6S  pkg C0805  page 156 : A = P12V_OCP_SFF ; B = GND
R2494  Q_RES  1K 1% CHIP  pkg 0402LF  page 115 : A = PWRGD_FAIL_CPU1_AB ; B = PWRGD_FAIL_CPU1_AB_R1
R4302  Q_RES  100 1% CHIP  pkg 0402LF  page 125 : A = PWRGD_DRAMPWRGD_CPU1_GH_LVC1_R2 ; B = PWRGD_DRAMPWRGD_CPU1_GH_LVC1_R

(kicad_pcb
	(version 20260206)
	(generator "pcbnew")
	(generator_version "10.0")
	(general
		(thickness 1.6)
		(legacy_teardrops no)
	)
	(paper "A4")
	(title_block
		(title "03242023_DA0F0TMBIJ0_F0T_Motherboard_J_brd_V01_OCP.brd")
		(comment 1 "Grand Teton / footprints 4385-4387 of 6105")
	)
	(layers
		(0 "F.Cu" signal "TOP")
		(4 "In1.Cu" signal "GND")
		(6 "In2.Cu" signal "IN1")
		(8 "In3.Cu" signal "GND1")
		(10 "In4.Cu" signal "IN2")
		(12 "In5.Cu" signal "GND2")
		(14 "In6.Cu" signal "IN3")
		(16 "In7.Cu" signal "GND3")
		(18 "In8.Cu" signal "VCC")
		(20 "In9.Cu" signal "VCC1")
		(22 "In10.Cu" signal "GND4")
		(24 "In11.Cu" signal "IN4")
		(26 "In12.Cu" signal "GND5")
		(28 "In13.Cu" signal "IN5")
		(30 "In14.Cu" signal "GND6")
		(32 "In15.Cu" signal "IN6")
		(34 "In16.Cu" signal "GND7")
		(2 "B.Cu" signal "BOTTOM")
		(9 "F.Adhes" user "F.Adhesive")
		(11 "B.Adhes" user "B.Adhesive")
		(13 "F.Paste" user "Package Geometry/Pastemask Top")
		(15 "B.Paste" user "Package Geometry/Pastemask Bottom")
		(5 "F.SilkS" user "Ref Des/Silkscreen Top")
		(7 "B.SilkS" user "Ref Des/Silkscreen Bottom")
		(1 "F.Mask" user "Board Geometry/Soldermask Top")
		(3 "B.Mask" user "Board Geometry/Soldermask Bottom")
		(17 "Dwgs.User" user "User.Drawings")
		(19 "Cmts.User" user "User.Comments")
		(21 "Eco1.User" user "User.Eco1")
		(23 "Eco2.User" user "User.Eco2")
		(25 "Edge.Cuts" user "Board Geometry/Outline")
		(27 "Margin" user)
		(31 "F.CrtYd" user "Package Geometry/Place Bound Top")
		(29 "B.CrtYd" user "Package Geometry/Place Bound Bottom")
		(35 "F.Fab" user "Ref Des/Assembly Top")
		(33 "B.Fab" user "Ref Des/Assembly Bottom")
	)
	(footprint ""
		(layer "B.Cu")
		(at 440.08802 -20.412456)
		(property "Reference" "PC2080"
			(at 0 0 0)
			(layer "B.SilkS")
			(hide yes)
			(effects
				(font
					(size 1.27 1.27)
				)
				(justify mirror)
			)
		)
		(property "Value" ""
			(at 0 0 0)
			(layer "B.Fab")
			(effects
				(font
					(size 1.27 1.27)
				)
				(justify mirror)
			)
		)
		(duplicate_pad_numbers_are_jumpers no)
		(fp_line
			(start -1.524 -0.762)
			(end -1.524 0.762)
			(stroke
				(width 0.1524)
				(type default)
			)
			(layer "B.SilkS")
		)
		(fp_line
			(start -1.524 0.762)
			(end 1.524 0.762)
			(stroke
				(width 0.1524)
				(type default)
			)
			(layer "B.SilkS")
		)
		(fp_line
			(start 1.524 -0.762)
			(end -1.524 -0.762)
			(stroke
				(width 0.1524)
				(type default)
			)
			(layer "B.SilkS")
		)
		(fp_line
			(start 1.524 0.762)
			(end 1.524 -0.762)
			(stroke
				(width 0.1524)
				(type default)
			)
			(layer "B.SilkS")
		)
		(fp_line
			(start -1.1049 -0.724916)
			(end 1.1049 -0.724916)
			(stroke
				(width 0.1)
				(type default)
			)
			(layer "B.Fab")
		)
		(fp_line
			(start -1.1049 0.724916)
			(end -1.1049 -0.724916)
			(stroke
				(width 0.1)
				(type default)
			)
			(layer "B.Fab")
		)
		(fp_line
			(start 1.1049 -0.724916)
			(end 1.1049 0.724916)
			(stroke
				(width 0.1)
				(type default)
			)
			(layer "B.Fab")
		)
		(fp_line
			(start 1.1049 0.724916)
			(end -1.1049 0.724916)
			(stroke
				(width 0.1)
				(type default)
			)
			(layer "B.Fab")
		)
		(pad "1" smd rect
			(at 0.889 0)
			(size 1.016 1.27)
			(layers "B.Cu" "B.Mask" "B.Paste")
			(net "P12V_OCP_SFF")
		)
		(pad "2" smd rect
			(at -0.889 0)
			(size 1.016 1.27)
			(layers "B.Cu" "B.Mask" "B.Paste")
			(net "GND")
		)
	)
	(footprint ""
		(layer "B.Cu")
		(at 64.990218 -317.897256 180)
		(property "Reference" "R2494"
			(at 0 0 0)
			(layer "B.SilkS")
			(hide yes)
			(effects
				(font
					(size 1.27 1.27)
				)
				(justify mirror)
			)
		)
		(property "Value" ""
			(at 0 0 0)
			(layer "B.Fab")
			(effects
				(font
					(size 1.27 1.27)
				)
				(justify mirror)
			)
		)
		(duplicate_pad_numbers_are_jumpers no)
		(fp_line
			(start 0.7874 0.4064)
			(end 0.7874 -0.4064)
			(stroke
				(width 0.1524)
				(type default)
			)
			(layer "B.SilkS")
		)
		(fp_line
			(start 0.7874 -0.4064)
			(end -0.7874 -0.4064)
			(stroke
				(width 0.1524)
				(type default)
			)
			(layer "B.SilkS")
		)
		(fp_line
			(start -0.7874 0.4064)
			(end 0.7874 0.4064)
			(stroke
				(width 0.1524)
				(type default)
			)
			(layer "B.SilkS")
		)
		(fp_line
			(start -0.7874 -0.4064)
			(end -0.7874 0.4064)
			(stroke
				(width 0.1524)
				(type default)
			)
			(layer "B.SilkS")
		)
		(fp_line
			(start 0.67945 0.3048)
			(end 0.67945 -0.305054)
			(stroke
				(width 0.1)
				(type default)
			)
			(layer "B.Fab")
		)
		(fp_line
			(start 0.67945 -0.305054)
			(end 0.12065 -0.305054)
			(stroke
				(width 0.1)
				(type default)
			)
			(layer "B.Fab")
		)
		(fp_line
			(start 0.12065 0.3048)
			(end 0.67945 0.3048)
			(stroke
				(width 0.1)
				(type default)
			)
			(layer "B.Fab")
		)
		(fp_line
			(start 0.12065 0.2794)
			(end 0.12065 0.3048)
			(stroke
				(width 0.1)
				(type default)
			)
			(layer "B.Fab")
		)
		(fp_line
			(start 0.12065 -0.2794)
			(end -0.12065 -0.2794)
			(stroke
				(width 0.1)
				(type default)
			)
			(layer "B.Fab")
		)
		(fp_line
			(start 0.12065 -0.305054)
			(end 0.12065 -0.2794)
			(stroke
				(width 0.1)
				(type default)
			)
			(layer "B.Fab")
		)
		(fp_line
			(start -0.120396 0.3048)
			(end -0.120396 0.2794)
			(stroke
				(width 0.1)
				(type default)
			)
			(layer "B.Fab")
		)
		(fp_line
			(start -0.120396 0.2794)
			(end 0.12065 0.2794)
			(stroke
				(width 0.1)
				(type default)
			)
			(layer "B.Fab")
		)
		(fp_line
			(start -0.12065 -0.2794)
			(end -0.12065 -0.3048)
			(stroke
				(width 0.1)
				(type default)
			)
			(layer "B.Fab")
		)
		(fp_line
			(start -0.12065 -0.3048)
			(end -0.67945 -0.3048)
			(stroke
				(width 0.1)
				(type default)
			)
			(layer "B.Fab")
		)
		(fp_line
			(start -0.67945 0.3048)
			(end -0.120396 0.3048)
			(stroke
				(width 0.1)
				(type default)
			)
			(layer "B.Fab")
		)
		(fp_line
			(start -0.67945 -0.3048)
			(end -0.67945 0.3048)
			(stroke
				(width 0.1)
				(type default)
			)
			(layer "B.Fab")
		)
		(pad "1" smd circle
			(at 0.40005 0)
			(size 0 0)
			(layers "B.Cu" "B.Mask" "B.Paste")
			(net "PWRGD_FAIL_CPU1_AB")
		)
		(pad "2" smd circle
			(at -0.40005 0)
			(size 0 0)
			(layers "B.Cu" "B.Mask" "B.Paste")
			(net "PWRGD_FAIL_CPU1_AB_R1")
		)
	)
	(footprint ""
		(layer "B.Cu")
		(at 170.673268 -196.013578 -90)
		(property "Reference" "R4302"
			(at 0 0 90)
			(layer "B.SilkS")
			(hide yes)
			(effects
				(font
					(size 1.27 1.27)
				)
				(justify mirror)
			)
		)
		(property "Value" ""
			(at 0 0 90)
			(layer "B.Fab")
			(effects
				(font
					(size 1.27 1.27)
				)
				(justify mirror)
			)
		)
		(duplicate_pad_numbers_are_jumpers no)
		(fp_line
			(start -0.7874 0.4064)
			(end 0.7874 0.4064)
			(stroke
				(width 0.1524)
				(type default)
			)
			(layer "B.SilkS")
		)
		(fp_line
			(start 0.7874 0.4064)
			(end 0.7874 -0.4064)
			(stroke
				(width 0.1524)
				(type default)
			)
			(layer "B.SilkS")
		)
		(fp_line
			(start -0.7874 -0.4064)
			(end -0.7874 0.4064)
			(stroke
				(width 0.1524)
				(type default)
			)
			(layer "B.SilkS")
		)
		(fp_line
			(start 0.7874 -0.4064)
			(end -0.7874 -0.4064)
			(stroke
				(width 0.1524)
				(type default)
			)
			(layer "B.SilkS")
		)
		(fp_line
			(start -0.67945 0.3048)
			(end -0.120396 0.3048)
			(stroke
				(width 0.1)
				(type default)
			)
			(layer "B.Fab")
		)
		(fp_line
			(start -0.120396 0.3048)
			(end -0.120396 0.2794)
			(stroke
				(width 0.1)
				(type default)
			)
			(layer "B.Fab")
		)
		(fp_line
			(start 0.12065 0.3048)
			(end 0.67945 0.3048)
			(stroke
				(width 0.1)
				(type default)
			)
			(layer "B.Fab")
		)
		(fp_line
			(start 0.67945 0.3048)
			(end 0.67945 -0.305054)
			(stroke
				(width 0.1)
				(type default)
			)
			(layer "B.Fab")
		)
		(fp_line
			(start -0.120396 0.2794)
			(end 0.12065 0.2794)
			(stroke
				(width 0.1)
				(type default)
			)
			(layer "B.Fab")
		)
		(fp_line
			(start 0.12065 0.2794)
			(end 0.12065 0.3048)
			(stroke
				(width 0.1)
				(type default)
			)
			(layer "B.Fab")
		)
		(fp_line
			(start -0.12065 -0.2794)
			(end -0.12065 -0.3048)
			(stroke
				(width 0.1)
				(type default)
			)
			(layer "B.Fab")
		)
		(fp_line
			(start 0.12065 -0.2794)
			(end -0.12065 -0.2794)
			(stroke
				(width 0.1)
				(type default)
			)
			(layer "B.Fab")
		)
		(fp_line
			(start -0.67945 -0.3048)
			(end -0.67945 0.3048)
			(stroke
				(width 0.1)
				(type default)
			)
			(layer "B.Fab")
		)
		(fp_line
			(start -0.12065 -0.3048)
			(end -0.67945 -0.3048)
			(stroke
				(width 0.1)
				(type default)
			)
			(layer "B.Fab")
		)
		(fp_line
			(start 0.12065 -0.305054)
			(end 0.12065 -0.2794)
			(stroke
				(width 0.1)
				(type default)
			)
			(layer "B.Fab")
		)
		(fp_line
			(start 0.67945 -0.305054)
			(end 0.12065 -0.305054)
			(stroke
				(width 0.1)
				(type default)
			)
			(layer "B.Fab")
		)
		(pad "1" smd circle
			(at 0.40005 0 90)
			(size 0 0)
			(layers "B.Cu" "B.Mask" "B.Paste")
			(net "PWRGD_DRAMPWRGD_CPU1_GH_LVC1_R2")
		)
		(pad "2" smd circle
			(at -0.40005 0 90)
			(size 0 0)
			(layers "B.Cu" "B.Mask" "B.Paste")
			(net "PWRGD_DRAMPWRGD_CPU1_GH_LVC1_R")
		)
	)
)
